# BASEBOARD_FAB2 (Tioga Pass) — schematic netlist excerpt (pin names and nets, part order shuffled) for the footprints in the layout excerpt that follows; sources: Cadence DE-HDL packaged netlist, KiCad conversion of Wiwynn_Tioga_Pass_MB.brd

C5G46  CAP_A  22.0UF 4V 20% X6S  pkg 0603V  page 242 : A = PVDDQ_ABC ; B = GND
C7U5  CAP  10UF 4V 20% X6S  pkg 0603LF  page 233 : A = PVPP_GHJ ; B = GND
C9M3  CAPP  68UF 16V 20% TANT  pkg 3018  page 195 : A = P12V_STBY ; B = GND
R1T5  RES  2.7K 1% EMPTY  pkg 0402  page 164 : A = P3V3_STBY ; B = FM_BOARD_REV_ID2

(kicad_pcb
	(version 20260206)
	(generator "pcbnew")
	(generator_version "10.0")
	(general
		(thickness 1.6)
		(legacy_teardrops no)
	)
	(paper "A4")
	(title_block
		(title "Wiwynn_Tioga_Pass_MB.brd")
		(comment 1 "Tioga Pass / footprints 2594-2597 of 4770")
	)
	(layers
		(0 "F.Cu" signal "TOP")
		(4 "In1.Cu" signal "L2GND")
		(6 "In2.Cu" signal "L3")
		(8 "In3.Cu" signal "L4GND")
		(10 "In4.Cu" signal "L5")
		(12 "In5.Cu" signal "L6GND")
		(14 "In6.Cu" signal "L7VCC")
		(16 "In7.Cu" signal "L8VCC")
		(18 "In8.Cu" signal "L9GND")
		(20 "In9.Cu" signal "L10")
		(22 "In10.Cu" signal "L11GND")
		(24 "In11.Cu" signal "L12")
		(26 "In12.Cu" signal "L13GND")
		(2 "B.Cu" signal "BOTTOM")
		(9 "F.Adhes" user "F.Adhesive")
		(11 "B.Adhes" user "B.Adhesive")
		(13 "F.Paste" user "Package Geometry/Pastemask Top")
		(15 "B.Paste" user "Package Geometry/Pastemask Bottom")
		(5 "F.SilkS" user "Ref Des/Silkscreen Top")
		(7 "B.SilkS" user "Ref Des/Silkscreen Bottom")
		(1 "F.Mask" user "Board Geometry/Soldermask Top")
		(3 "B.Mask" user "Board Geometry/Soldermask Bottom")
		(17 "Dwgs.User" user "User.Drawings")
		(19 "Cmts.User" user "User.Comments")
		(21 "Eco1.User" user "User.Eco1")
		(23 "Eco2.User" user "User.Eco2")
		(25 "Edge.Cuts" user "Board Geometry/Outline")
		(27 "Margin" user)
		(31 "F.CrtYd" user "Package Geometry/Place Bound Top")
		(29 "B.CrtYd" user "Package Geometry/Place Bound Bottom")
		(35 "F.Fab" user "Ref Des/Assembly Top")
		(33 "B.Fab" user "Ref Des/Assembly Bottom")
	)
	(footprint ""
		(layer "B.Cu")
		(at 18.6309 -124.5616 180)
		(property "Reference" "C9M3"
			(at 3.03657 4.9784 270)
			(unlocked yes)
			(layer "B.SilkS")
			(effects
				(font
					(size 0.7874 0.5842)
					(thickness 0.1524)
				)
				(justify mirror)
			)
		)
		(property "Value" ""
			(at 0 0 0)
			(layer "B.Fab")
			(effects
				(font
					(size 1.27 1.27)
				)
				(justify mirror)
			)
		)
		(duplicate_pad_numbers_are_jumpers no)
		(fp_line
			(start 2.563114 1.633728)
			(end 1.6002 1.633728)
			(stroke
				(width 0.1524)
				(type default)
			)
			(layer "B.SilkS")
		)
		(fp_line
			(start 2.563114 -1.616456)
			(end 2.563114 1.633728)
			(stroke
				(width 0.1524)
				(type default)
			)
			(layer "B.SilkS")
		)
		(fp_line
			(start 2.286 7.366)
			(end 2.286 1.632712)
			(stroke
				(width 0.1524)
				(type default)
			)
			(layer "B.SilkS")
		)
		(fp_line
			(start 2.286 7.366)
			(end 1.60147 7.366)
			(stroke
				(width 0.1524)
				(type default)
			)
			(layer "B.SilkS")
		)
		(fp_line
			(start 1.6002 -1.616456)
			(end 2.563114 -1.616456)
			(stroke
				(width 0.1524)
				(type default)
			)
			(layer "B.SilkS")
		)
		(fp_line
			(start -1.6002 -1.616456)
			(end -2.504948 -1.616456)
			(stroke
				(width 0.1524)
				(type default)
			)
			(layer "B.SilkS")
		)
		(fp_line
			(start -2.286 7.366)
			(end -1.600708 7.366)
			(stroke
				(width 0.1524)
				(type default)
			)
			(layer "B.SilkS")
		)
		(fp_line
			(start -2.286 7.366)
			(end -2.286 1.63195)
			(stroke
				(width 0.1524)
				(type default)
			)
			(layer "B.SilkS")
		)
		(fp_line
			(start -2.504948 1.633728)
			(end -1.6002 1.633728)
			(stroke
				(width 0.1524)
				(type default)
			)
			(layer "B.SilkS")
		)
		(fp_line
			(start -2.504948 -1.616456)
			(end -2.504948 1.633728)
			(stroke
				(width 0.1524)
				(type default)
			)
			(layer "B.SilkS")
		)
		(fp_rect
			(start 2.286 7.366)
			(end -2.286 -0.254)
			(stroke
				(width 0)
				(type default)
			)
			(fill no)
			(layer "B.CrtYd")
		)
		(fp_line
			(start 2.286 7.366)
			(end 2.286 -0.254)
			(stroke
				(width 0.1)
				(type default)
			)
			(layer "B.Fab")
		)
		(fp_line
			(start 2.286 -0.254)
			(end -2.286 -0.254)
			(stroke
				(width 0.1)
				(type default)
			)
			(layer "B.Fab")
		)
		(fp_line
			(start -2.286 7.366)
			(end 2.286 7.366)
			(stroke
				(width 0.1)
				(type default)
			)
			(layer "B.Fab")
		)
		(fp_line
			(start -2.286 -0.254)
			(end -2.286 7.366)
			(stroke
				(width 0.1)
				(type default)
			)
			(layer "B.Fab")
		)
		(pad "1" smd rect
			(at 0 0)
			(size 2.54 3.048)
			(layers "B.Cu" "B.Mask" "B.Paste")
			(net "P12V_STBY")
		)
		(pad "2" smd rect
			(at 0 7.112)
			(size 2.54 3.048)
			(layers "B.Cu" "B.Mask" "B.Paste")
			(net "GND")
		)
	)
	(footprint ""
		(layer "B.Cu")
		(at 410.591 -48.768)
		(property "Reference" "R1T5"
			(at 0 0 0)
			(layer "B.SilkS")
			(hide yes)
			(effects
				(font
					(size 1.27 1.27)
				)
				(justify mirror)
			)
		)
		(property "Value" ""
			(at 0 0 0)
			(layer "B.Fab")
			(effects
				(font
					(size 1.27 1.27)
				)
				(justify mirror)
			)
		)
		(duplicate_pad_numbers_are_jumpers no)
		(fp_poly
			(pts
				(xy 0.2794 -0.1016) (xy -0.2794 -0.1016) (xy -0.2794 0.9906) (xy 0.2794 0.9906)
			)
			(stroke
				(width 0)
				(type default)
			)
			(fill no)
			(layer "B.CrtYd")
		)
		(fp_line
			(start -0.2794 -0.1016)
			(end 0.2794 -0.1016)
			(stroke
				(width 0.1)
				(type default)
			)
			(layer "B.Fab")
		)
		(fp_line
			(start -0.2794 0.9906)
			(end -0.2794 -0.1016)
			(stroke
				(width 0.1)
				(type default)
			)
			(layer "B.Fab")
		)
		(fp_line
			(start 0.2794 -0.1016)
			(end 0.2794 0.9906)
			(stroke
				(width 0.1)
				(type default)
			)
			(layer "B.Fab")
		)
		(fp_line
			(start 0.2794 0.9906)
			(end -0.2794 0.9906)
			(stroke
				(width 0.1)
				(type default)
			)
			(layer "B.Fab")
		)
		(pad "1" smd rect
			(at 0 0 180)
			(size 0.508 0.508)
			(layers "B.Cu" "B.Mask" "B.Paste")
			(net "P3V3_STBY")
		)
		(pad "2" smd rect
			(at 0 0.889 180)
			(size 0.508 0.508)
			(layers "B.Cu" "B.Mask" "B.Paste")
			(net "FM_BOARD_REV_ID2")
		)
	)
	(footprint ""
		(layer "B.Cu")
		(at 155.194 1.7018 90)
		(property "Reference" "C7U5"
			(at 0 0 90)
			(layer "B.SilkS")
			(hide yes)
			(effects
				(font
					(size 1.27 1.27)
				)
				(justify mirror)
			)
		)
		(property "Value" ""
			(at 0 0 90)
			(layer "B.Fab")
			(effects
				(font
					(size 1.27 1.27)
				)
				(justify mirror)
			)
		)
		(duplicate_pad_numbers_are_jumpers no)
		(fp_poly
			(pts
				(xy 0.4953 -0.2032) (xy -0.4953 -0.2032) (xy -0.4953 1.6002) (xy 0.4953 1.6002)
			)
			(stroke
				(width 0)
				(type default)
			)
			(fill no)
			(layer "B.CrtYd")
		)
		(fp_line
			(start 0.4953 -0.2032)
			(end -0.4953 -0.2032)
			(stroke
				(width 0.1)
				(type default)
			)
			(layer "B.Fab")
		)
		(fp_line
			(start -0.4953 -0.2032)
			(end -0.4953 1.6002)
			(stroke
				(width 0.1)
				(type default)
			)
			(layer "B.Fab")
		)
		(fp_line
			(start 0.4953 1.6002)
			(end 0.4953 -0.2032)
			(stroke
				(width 0.1)
				(type default)
			)
			(layer "B.Fab")
		)
		(fp_line
			(start -0.4953 1.6002)
			(end 0.4953 1.6002)
			(stroke
				(width 0.1)
				(type default)
			)
			(layer "B.Fab")
		)
		(pad "1" smd rect
			(at 0 0 270)
			(size 0.762 0.889)
			(layers "B.Cu" "B.Mask" "B.Paste")
			(net "PVPP_GHJ")
		)
		(pad "2" smd rect
			(at 0 1.397 270)
			(size 0.762 0.889)
			(layers "B.Cu" "B.Mask" "B.Paste")
			(net "GND")
		)
		(zone
			(layer "B.Cu")
			(hatch none 0.5)
			(connect_pads
				(clearance 0)
			)
			(min_thickness 0.25)
			(keepout
				(tracks not_allowed)
				(vias allowed)
				(pads allowed)
				(copperpour not_allowed)
				(footprints allowed)
			)
			(placement
				(enabled no)
				(sheetname "")
			)
			(fill
				(thermal_gap 0.5)
				(thermal_bridge_width 0.5)
				(island_removal_mode 0)
			)
			(polygon
				(pts
					(xy 155.6385 1.3208) (xy 155.6385 2.0828) (xy 156.1465 2.0828) (xy 156.1465 1.3208)
				)
			)
		)
	)
	(footprint ""
		(layer "B.Cu")
		(at 266.397232 -12.954 90)
		(property "Reference" "C5G46"
			(at -1.14681 0.76708 180)
			(unlocked yes)
			(layer "B.SilkS")
			(effects
				(font
					(size 0.7874 0.5842)
					(thickness 0.1524)
				)
				(justify mirror)
			)
		)
		(property "Value" ""
			(at 0 0 90)
			(layer "B.Fab")
			(effects
				(font
					(size 1.27 1.27)
				)
				(justify mirror)
			)
		)
		(duplicate_pad_numbers_are_jumpers no)
		(fp_rect
			(start -0.4953 -0.2032)
			(end 0.4953 1.6002)
			(stroke
				(width 0)
				(type default)
			)
			(fill no)
			(layer "B.CrtYd")
		)
		(fp_line
			(start 0.4953 -0.2032)
			(end -0.4953 -0.2032)
			(stroke
				(width 0.1)
				(type default)
			)
			(layer "B.Fab")
		)
		(fp_line
			(start -0.4953 -0.2032)
			(end -0.4953 1.6002)
			(stroke
				(width 0.1)
				(type default)
			)
			(layer "B.Fab")
		)
		(fp_line
			(start 0.4953 1.6002)
			(end 0.4953 -0.2032)
			(stroke
				(width 0.1)
				(type default)
			)
			(layer "B.Fab")
		)
		(fp_line
			(start -0.4953 1.6002)
			(end 0.4953 1.6002)
			(stroke
				(width 0.1)
				(type default)
			)
			(layer "B.Fab")
		)
		(pad "1" smd rect
			(at 0 0 270)
			(size 0.762 0.889)
			(layers "B.Cu" "B.Mask" "B.Paste")
			(net "PVDDQ_ABC")
		)
		(pad "2" smd rect
			(at 0 1.397 270)
			(size 0.762 0.889)
			(layers "B.Cu" "B.Mask" "B.Paste")
			(net "GND")
		)
		(zone
			(layer "B.Cu")
			(hatch none 0.5)
			(connect_pads
				(clearance 0)
			)
			(min_thickness 0.25)
			(keepout
				(tracks not_allowed)
				(vias allowed)
				(pads allowed)
				(copperpour not_allowed)
				(footprints allowed)
			)
			(placement
				(enabled no)
				(sheetname "")
			)
			(fill
				(thermal_gap 0.5)
				(thermal_bridge_width 0.5)
				(island_removal_mode 0)
			)
			(polygon
				(pts
					(xy 266.841732 -12.573) (xy 267.349732 -12.573) (xy 267.349732 -13.335) (xy 266.841732 -13.335)
				)
			)
		)
	)
)
